(kicad_pcb
	(version 20260206)
	(generator "pcbnew")
	(generator_version "10.0")
	(general
		(thickness 1.6)
		(legacy_teardrops no)
	)
	(paper "A4")
	(title_block
		(title "panther-plus-userver — 13130-1b_20150205.brd")
		(comment 1 "Honey Badger (Wiwynn) / footprints 543-549 of 1509")
	)
	(layers
		(0 "F.Cu" signal "TOP")
		(4 "In1.Cu" signal "L2")
		(6 "In2.Cu" signal "L3")
		(8 "In3.Cu" signal "L4")
		(10 "In4.Cu" signal "L5")
		(12 "In5.Cu" signal "L6")
		(14 "In6.Cu" signal "L7")
		(16 "In7.Cu" signal "L8")
		(18 "In8.Cu" signal "L9")
		(20 "In9.Cu" signal "L10")
		(22 "In10.Cu" signal "L11")
		(2 "B.Cu" signal "BOTTOM")
		(9 "F.Adhes" user "F.Adhesive")
		(11 "B.Adhes" user "B.Adhesive")
		(13 "F.Paste" user "Package Geometry/Pastemask Top")
		(15 "B.Paste" user "Package Geometry/Pastemask Bottom")
		(5 "F.SilkS" user "Ref Des/Silkscreen Top")
		(7 "B.SilkS" user "Ref Des/Silkscreen Bottom")
		(1 "F.Mask" user "Board Geometry/Soldermask Top")
		(3 "B.Mask" user "Board Geometry/Soldermask Bottom")
		(17 "Dwgs.User" user "User.Drawings")
		(19 "Cmts.User" user "User.Comments")
		(21 "Eco1.User" user "User.Eco1")
		(23 "Eco2.User" user "User.Eco2")
		(25 "Edge.Cuts" user "Board Geometry/Outline")
		(27 "Margin" user)
		(31 "F.CrtYd" user "Package Geometry/Place Bound Top")
		(29 "B.CrtYd" user "Package Geometry/Place Bound Bottom")
		(35 "F.Fab" user "Ref Des/Assembly Top")
		(33 "B.Fab" user "Ref Des/Assembly Bottom")
	)
	(footprint ""
		(layer "F.Cu")
		(at 148.717 -20.701)
		(property "Reference" "C46"
			(at 0 0 0)
			(layer "F.SilkS")
			(hide yes)
			(effects
				(font
					(size 1.27 1.27)
				)
			)
		)
		(property "Value" "SCD1U10V2KX-5GP"
			(at 1.1811 -2.7051 0)
			(unlocked yes)
			(layer "F.Fab")
			(hide yes)
			(effects
				(font
					(size 1.016 1.016)
					(thickness 0.1524)
				)
			)
		)
		(property "Device Type" "C402H22"
			(at 1.1811 -4.2291 0)
			(unlocked yes)
			(layer "F.Fab")
			(hide yes)
			(effects
				(font
					(size 1.016 1.016)
					(thickness 0.1524)
				)
			)
		)
		(duplicate_pad_numbers_are_jumpers no)
		(fp_rect
			(start -0.381 0.7366)
			(end 0.381 -0.7366)
			(stroke
				(width 0)
				(type default)
			)
			(fill no)
			(layer "F.CrtYd")
		)
		(fp_rect
			(start -0.381 0.7366)
			(end 0.381 -0.7366)
			(stroke
				(width 0)
				(type default)
			)
			(fill no)
			(layer "F.Fab")
		)
		(pad "1" smd custom
			(at 0 -0.4572)
			(size 0.1143 0.1143)
			(layers "F.Cu" "F.Mask" "F.Paste")
			(net "P1V2_FPGA_D")
			(options
				(clearance outline)
				(anchor circle)
			)
			(primitives
				(gr_poly
					(pts
						(arc
							(start -0.254 -0.1778)
							(mid -0.239121 -0.213721)
							(end -0.2032 -0.2286)
						)
						(arc
							(start 0.2032 -0.2286)
							(mid 0.239121 -0.213721)
							(end 0.254 -0.1778)
						)
						(arc
							(start 0.254 0.1778)
							(mid 0.239121 0.213721)
							(end 0.2032 0.2286)
						)
						(arc
							(start -0.2032 0.2286)
							(mid -0.239121 0.213721)
							(end -0.254 0.1778)
						)
					)
					(width 0)
					(fill yes)
				)
			)
		)
		(pad "2" smd custom
			(at 0 0.4572)
			(size 0.1143 0.1143)
			(layers "F.Cu" "F.Mask" "F.Paste")
			(net "GND")
			(options
				(clearance outline)
				(anchor circle)
			)
			(primitives
				(gr_poly
					(pts
						(arc
							(start -0.254 -0.1778)
							(mid -0.239121 -0.213721)
							(end -0.2032 -0.2286)
						)
						(arc
							(start 0.2032 -0.2286)
							(mid 0.239121 -0.213721)
							(end 0.254 -0.1778)
						)
						(arc
							(start 0.254 0.1778)
							(mid 0.239121 0.213721)
							(end 0.2032 0.2286)
						)
						(arc
							(start -0.2032 0.2286)
							(mid -0.239121 0.213721)
							(end -0.254 0.1778)
						)
					)
					(width 0)
					(fill yes)
				)
			)
		)
	)
	(footprint ""
		(layer "F.Cu")
		(at 158.242 -28.956 180)
		(property "Reference" "R147"
			(at 0 0 180)
			(layer "F.SilkS")
			(hide yes)
			(effects
				(font
					(size 1.27 1.27)
				)
			)
		)
		(property "Value" "4K7R2F-GP"
			(at 0.064008 -3.993896 180)
			(unlocked yes)
			(layer "F.Fab")
			(hide yes)
			(effects
				(font
					(size 1.016 1.016)
					(thickness 0.1524)
				)
			)
		)
		(property "Device Type" "R402H16"
			(at 0.064008 -5.517896 180)
			(unlocked yes)
			(layer "F.Fab")
			(hide yes)
			(effects
				(font
					(size 1.016 1.016)
					(thickness 0.1524)
				)
			)
		)
		(duplicate_pad_numbers_are_jumpers no)
		(fp_rect
			(start -0.381 0.8382)
			(end 0.381 -0.8382)
			(stroke
				(width 0)
				(type default)
			)
			(fill no)
			(layer "F.CrtYd")
		)
		(fp_rect
			(start -0.381 0.8382)
			(end 0.381 -0.8382)
			(stroke
				(width 0)
				(type default)
			)
			(fill no)
			(layer "F.Fab")
		)
		(pad "1" smd custom
			(at 0 -0.4318 180)
			(size 0.127 0.127)
			(layers "F.Cu" "F.Mask" "F.Paste")
			(net "P3V3_STBY")
			(options
				(clearance outline)
				(anchor circle)
			)
			(primitives
				(gr_poly
					(pts
						(arc
							(start -0.2032 -0.2794)
							(mid -0.239121 -0.264521)
							(end -0.254 -0.2286)
						)
						(arc
							(start -0.254 0.2286)
							(mid -0.239121 0.264521)
							(end -0.2032 0.2794)
						)
						(arc
							(start 0.2032 0.2794)
							(mid 0.239121 0.264521)
							(end 0.254 0.2286)
						)
						(arc
							(start 0.254 -0.2286)
							(mid 0.239121 -0.264521)
							(end 0.2032 -0.2794)
						)
					)
					(width 0)
					(fill yes)
				)
			)
		)
		(pad "2" smd custom
			(at 0 0.4318 180)
			(size 0.127 0.127)
			(layers "F.Cu" "F.Mask" "F.Paste")
			(net "FPGA_READY#")
			(options
				(clearance outline)
				(anchor circle)
			)
			(primitives
				(gr_poly
					(pts
						(arc
							(start -0.2032 -0.2794)
							(mid -0.239121 -0.264521)
							(end -0.254 -0.2286)
						)
						(arc
							(start -0.254 0.2286)
							(mid -0.239121 0.264521)
							(end -0.2032 0.2794)
						)
						(arc
							(start 0.2032 0.2794)
							(mid 0.239121 0.264521)
							(end 0.254 0.2286)
						)
						(arc
							(start 0.254 -0.2286)
							(mid 0.239121 -0.264521)
							(end 0.2032 -0.2794)
						)
					)
					(width 0)
					(fill yes)
				)
			)
		)
	)
	(footprint ""
		(layer "F.Cu")
		(at 6.839966 -46.479968)
		(property "Reference" "U1"
			(at 0 0 0)
			(layer "F.SilkS")
			(hide yes)
			(effects
				(font
					(size 1.27 1.27)
				)
			)
		)
		(property "Value" "TMP75AIDGKR-GP"
			(at -0.1143 -9.1948 0)
			(unlocked yes)
			(layer "F.Fab")
			(hide yes)
			(effects
				(font
					(size 1.016 1.016)
					(thickness 0.1524)
				)
			)
		)
		(property "Device Type" "MSOP8-1H44"
			(at -0.1143 -10.795 0)
			(unlocked yes)
			(layer "F.Fab")
			(hide yes)
			(effects
				(font
					(size 1.016 1.016)
					(thickness 0.1524)
				)
			)
		)
		(duplicate_pad_numbers_are_jumpers no)
		(fp_line
			(start -1.7018 -1.016)
			(end -1.7018 1.016)
			(stroke
				(width 0.1524)
				(type default)
			)
			(layer "F.SilkS")
		)
		(fp_line
			(start -1.7018 -0.4318)
			(end -1.27 0)
			(stroke
				(width 0.1524)
				(type default)
			)
			(layer "F.SilkS")
		)
		(fp_line
			(start -1.7018 1.016)
			(end 1.0668 1.016)
			(stroke
				(width 0.1524)
				(type default)
			)
			(layer "F.SilkS")
		)
		(fp_line
			(start -1.651 1.0668)
			(end -1.651 2.794)
			(stroke
				(width 0.254)
				(type default)
			)
			(layer "F.SilkS")
		)
		(fp_line
			(start -1.27 0)
			(end -1.7018 0.4318)
			(stroke
				(width 0.1524)
				(type default)
			)
			(layer "F.SilkS")
		)
		(fp_line
			(start 1.0668 -1.016)
			(end -1.7018 -1.016)
			(stroke
				(width 0.1524)
				(type default)
			)
			(layer "F.SilkS")
		)
		(fp_line
			(start 1.0668 1.016)
			(end 1.0668 -1.016)
			(stroke
				(width 0.1524)
				(type default)
			)
			(layer "F.SilkS")
		)
		(fp_poly
			(pts
				(xy -1.1684 1.016) (xy 1.0668 1.016) (xy 1.0668 -1.016) (xy -1.1684 -1.016)
			)
			(stroke
				(width 0)
				(type default)
			)
			(fill yes)
			(layer "F.SilkS")
		)
		(fp_rect
			(start -1.7526 2.8194)
			(end 1.7526 -2.8194)
			(stroke
				(width 0)
				(type default)
			)
			(fill no)
			(layer "F.CrtYd")
		)
		(fp_rect
			(start -1.7526 2.8194)
			(end 1.7526 -2.8194)
			(stroke
				(width 0)
				(type default)
			)
			(fill no)
			(layer "F.Fab")
		)
		(pad "1" smd rect
			(at -0.97536 1.99136)
			(size 0.3556 1.397)
			(layers "F.Cu" "F.Mask" "F.Paste")
			(net "TEMP_1_DATA")
		)
		(pad "2" smd rect
			(at -0.32512 1.99136)
			(size 0.3556 1.397)
			(layers "F.Cu" "F.Mask" "F.Paste")
			(net "TEMP_1_CLK")
		)
		(pad "3" smd rect
			(at 0.32512 1.99136)
			(size 0.3556 1.397)
			(layers "F.Cu" "F.Mask" "F.Paste")
			(net "TEMP_1_ALERT#")
		)
		(pad "4" smd rect
			(at 0.97536 1.99136)
			(size 0.3556 1.397)
			(layers "F.Cu" "F.Mask" "F.Paste")
			(net "GND")
		)
		(pad "5" smd rect
			(at 0.97536 -1.99136)
			(size 0.3556 1.397)
			(layers "F.Cu" "F.Mask" "F.Paste")
			(net "TEMP_1_A2")
		)
		(pad "6" smd rect
			(at 0.32512 -1.99136)
			(size 0.3556 1.397)
			(layers "F.Cu" "F.Mask" "F.Paste")
			(net "TEMP_1_A1")
		)
		(pad "7" smd rect
			(at -0.32512 -1.99136)
			(size 0.3556 1.397)
			(layers "F.Cu" "F.Mask" "F.Paste")
			(net "TEMP_1_A0")
		)
		(pad "8" smd rect
			(at -0.97536 -1.99136)
			(size 0.3556 1.397)
			(layers "F.Cu" "F.Mask" "F.Paste")
			(net "P3V3_STBY")
		)
	)
	(footprint ""
		(layer "F.Cu")
		(at 70.231 -36.957 90)
		(property "Reference" "R99"
			(at 0 0 90)
			(layer "F.SilkS")
			(hide yes)
			(effects
				(font
					(size 1.27 1.27)
				)
			)
		)
		(property "Value" "10KR2F-2-GP"
			(at 0.064008 -3.993896 90)
			(unlocked yes)
			(layer "F.Fab")
			(hide yes)
			(effects
				(font
					(size 1.016 1.016)
					(thickness 0.1524)
				)
			)
		)
		(property "Device Type" "R402H16"
			(at 0.064008 -5.517896 90)
			(unlocked yes)
			(layer "F.Fab")
			(hide yes)
			(effects
				(font
					(size 1.016 1.016)
					(thickness 0.1524)
				)
			)
		)
		(duplicate_pad_numbers_are_jumpers no)
		(fp_rect
			(start -0.381 0.8382)
			(end 0.381 -0.8382)
			(stroke
				(width 0)
				(type default)
			)
			(fill no)
			(layer "F.CrtYd")
		)
		(fp_rect
			(start -0.381 0.8382)
			(end 0.381 -0.8382)
			(stroke
				(width 0)
				(type default)
			)
			(fill no)
			(layer "F.Fab")
		)
		(pad "1" smd custom
			(at 0 -0.4318 90)
			(size 0.127 0.127)
			(layers "F.Cu" "F.Mask" "F.Paste")
			(net "P3V3_CPU")
			(options
				(clearance outline)
				(anchor circle)
			)
			(primitives
				(gr_poly
					(pts
						(arc
							(start -0.2032 -0.2794)
							(mid -0.239121 -0.264521)
							(end -0.254 -0.2286)
						)
						(arc
							(start -0.254 0.2286)
							(mid -0.239121 0.264521)
							(end -0.2032 0.2794)
						)
						(arc
							(start 0.2032 0.2794)
							(mid 0.239121 0.264521)
							(end 0.254 0.2286)
						)
						(arc
							(start 0.254 -0.2286)
							(mid 0.239121 -0.264521)
							(end 0.2032 -0.2794)
						)
					)
					(width 0)
					(fill yes)
				)
			)
		)
		(pad "2" smd custom
			(at 0 0.4318 90)
			(size 0.127 0.127)
			(layers "F.Cu" "F.Mask" "F.Paste")
			(net "PMU_SLP_S3#")
			(options
				(clearance outline)
				(anchor circle)
			)
			(primitives
				(gr_poly
					(pts
						(arc
							(start -0.2032 -0.2794)
							(mid -0.239121 -0.264521)
							(end -0.254 -0.2286)
						)
						(arc
							(start -0.254 0.2286)
							(mid -0.239121 0.264521)
							(end -0.2032 0.2794)
						)
						(arc
							(start 0.2032 0.2794)
							(mid 0.239121 0.264521)
							(end 0.254 0.2286)
						)
						(arc
							(start 0.254 -0.2286)
							(mid 0.239121 -0.264521)
							(end 0.2032 -0.2794)
						)
					)
					(width 0)
					(fill yes)
				)
			)
		)
	)
	(footprint ""
		(layer "F.Cu")
		(at 31.4198 -36.2204)
		(property "Reference" "R277"
			(at 0 0 0)
			(layer "F.SilkS")
			(hide yes)
			(effects
				(font
					(size 1.27 1.27)
				)
			)
		)
		(property "Value" "51R2F-2-GP"
			(at 0.064008 -3.993896 0)
			(unlocked yes)
			(layer "F.Fab")
			(hide yes)
			(effects
				(font
					(size 1.016 1.016)
					(thickness 0.1524)
				)
			)
		)
		(property "Device Type" "R402H16"
			(at 0.064008 -5.517896 0)
			(unlocked yes)
			(layer "F.Fab")
			(hide yes)
			(effects
				(font
					(size 1.016 1.016)
					(thickness 0.1524)
				)
			)
		)
		(duplicate_pad_numbers_are_jumpers no)
		(fp_rect
			(start -0.381 0.8382)
			(end 0.381 -0.8382)
			(stroke
				(width 0)
				(type default)
			)
			(fill no)
			(layer "F.CrtYd")
		)
		(fp_rect
			(start -0.381 0.8382)
			(end 0.381 -0.8382)
			(stroke
				(width 0)
				(type default)
			)
			(fill no)
			(layer "F.Fab")
		)
		(pad "1" smd custom
			(at 0 -0.4318)
			(size 0.127 0.127)
			(layers "F.Cu" "F.Mask" "F.Paste")
			(net "P1V0_STBY")
			(options
				(clearance outline)
				(anchor circle)
			)
			(primitives
				(gr_poly
					(pts
						(arc
							(start -0.2032 -0.2794)
							(mid -0.239121 -0.264521)
							(end -0.254 -0.2286)
						)
						(arc
							(start -0.254 0.2286)
							(mid -0.239121 0.264521)
							(end -0.2032 0.2794)
						)
						(arc
							(start 0.2032 0.2794)
							(mid 0.239121 0.264521)
							(end 0.254 0.2286)
						)
						(arc
							(start 0.254 -0.2286)
							(mid 0.239121 -0.264521)
							(end 0.2032 -0.2794)
						)
					)
					(width 0)
					(fill yes)
				)
			)
		)
		(pad "2" smd custom
			(at 0 0.4318)
			(size 0.127 0.127)
			(layers "F.Cu" "F.Mask" "F.Paste")
			(net "XDP_SOC_CPU_TDI")
			(options
				(clearance outline)
				(anchor circle)
			)
			(primitives
				(gr_poly
					(pts
						(arc
							(start -0.2032 -0.2794)
							(mid -0.239121 -0.264521)
							(end -0.254 -0.2286)
						)
						(arc
							(start -0.254 0.2286)
							(mid -0.239121 0.264521)
							(end -0.2032 0.2794)
						)
						(arc
							(start 0.2032 0.2794)
							(mid 0.239121 0.264521)
							(end 0.254 0.2286)
						)
						(arc
							(start 0.254 -0.2286)
							(mid 0.239121 -0.264521)
							(end 0.2032 -0.2794)
						)
					)
					(width 0)
					(fill yes)
				)
			)
		)
	)
	(footprint ""
		(layer "F.Cu")
		(at 172.847 -42.164 90)
		(property "Reference" "PU17"
			(at 0 0 90)
			(layer "F.SilkS")
			(hide yes)
			(effects
				(font
					(size 1.27 1.27)
				)
			)
		)
		(property "Value" "TPS79301DBVR-GP"
			(at -2.914396 -2.576322 90)
			(unlocked yes)
			(layer "F.Fab")
			(hide yes)
			(effects
				(font
					(size 1.016 1.016)
					(thickness 0.1524)
				)
			)
		)
		(property "Device Type" "SOT-6-1H58"
			(at -2.914396 -1.052322 90)
			(unlocked yes)
			(layer "F.Fab")
			(hide yes)
			(effects
				(font
					(size 1.016 1.016)
					(thickness 0.1524)
				)
			)
		)
		(duplicate_pad_numbers_are_jumpers no)
		(fp_line
			(start 1.2573 -0.4064)
			(end -1.7018 -0.4064)
			(stroke
				(width 0.1524)
				(type default)
			)
			(layer "F.SilkS")
		)
		(fp_line
			(start -1.7018 -0.4064)
			(end -1.7018 0.4064)
			(stroke
				(width 0.1524)
				(type default)
			)
			(layer "F.SilkS")
		)
		(fp_line
			(start -1.7018 -0.3175)
			(end -1.397 -0.0127)
			(stroke
				(width 0.1524)
				(type default)
			)
			(layer "F.SilkS")
		)
		(fp_line
			(start -1.397 -0.0127)
			(end -1.7018 0.2921)
			(stroke
				(width 0.1524)
				(type default)
			)
			(layer "F.SilkS")
		)
		(fp_line
			(start 1.2573 0.4064)
			(end 1.2573 -0.4064)
			(stroke
				(width 0.1524)
				(type default)
			)
			(layer "F.SilkS")
		)
		(fp_line
			(start -1.6637 0.4064)
			(end -1.6637 1.5748)
			(stroke
				(width 0.254)
				(type default)
			)
			(layer "F.SilkS")
		)
		(fp_line
			(start -1.7018 0.4064)
			(end 1.2573 0.4064)
			(stroke
				(width 0.1524)
				(type default)
			)
			(layer "F.SilkS")
		)
		(fp_poly
			(pts
				(xy -1.2573 0.4064) (xy 1.2573 0.4064) (xy 1.2573 -0.4064) (xy -1.2573 -0.4064)
			)
			(stroke
				(width 0)
				(type default)
			)
			(fill yes)
			(layer "F.SilkS")
		)
		(fp_poly
			(pts
				(xy -1.7018 1.053846) (xy -1.7018 -1.053846) (xy -1.38176 -1.053846) (xy -1.38176 -1.780794) (xy 1.38176 -1.780794)
				(xy 1.38176 -1.053846) (xy 1.7018 -1.053846) (xy 1.7018 1.053846) (xy 1.38176 1.053846) (xy 1.38176 1.780794)
				(xy -1.38176 1.780794) (xy -1.38176 1.053846)
			)
			(stroke
				(width 0)
				(type default)
			)
			(fill no)
			(layer "F.CrtYd")
		)
		(fp_poly
			(pts
				(xy -1.7018 1.053846) (xy -1.7018 -1.053846) (xy -1.38176 -1.053846) (xy -1.38176 -1.780794) (xy 1.38176 -1.780794)
				(xy 1.38176 -1.053846) (xy 1.7018 -1.053846) (xy 1.7018 1.053846) (xy 1.38176 1.053846) (xy 1.38176 1.780794)
				(xy -1.38176 1.780794) (xy -1.38176 1.053846)
			)
			(stroke
				(width 0)
				(type default)
			)
			(fill no)
			(layer "F.Fab")
		)
		(pad "1" smd rect
			(at -0.94996 1.183894 90)
			(size 0.6096 0.9398)
			(layers "F.Cu" "F.Mask" "F.Paste")
			(net "P3V3_STBY")
		)
		(pad "2" smd rect
			(at 0 1.183894 90)
			(size 0.6096 0.9398)
			(layers "F.Cu" "F.Mask" "F.Paste")
			(net "GND")
		)
		(pad "3" smd rect
			(at 0.94996 1.183894 90)
			(size 0.6096 0.9398)
			(layers "F.Cu" "F.Mask" "F.Paste")
			(net "P3V3_STBY")
		)
		(pad "4" smd rect
			(at 0.94996 -1.183894 90)
			(size 0.6096 0.9398)
			(layers "F.Cu" "F.Mask" "F.Paste")
			(net "P2V5_STBY_BYPASS")
		)
		(pad "5" smd rect
			(at 0 -1.183894 90)
			(size 0.6096 0.9398)
			(layers "F.Cu" "F.Mask" "F.Paste")
			(net "P2V5_STBY_FB")
		)
		(pad "6" smd rect
			(at -0.94996 -1.183894 90)
			(size 0.6096 0.9398)
			(layers "F.Cu" "F.Mask" "F.Paste")
			(net "P2V5_STBY_OUT")
		)
	)
	(footprint ""
		(layer "F.Cu")
		(at 186.817 -45.974 180)
		(property "Reference" "R219"
			(at 0 0 180)
			(layer "F.SilkS")
			(hide yes)
			(effects
				(font
					(size 1.27 1.27)
				)
			)
		)
		(property "Value" "100R2F-L1-GP-U"
			(at 0.064008 -3.993896 180)
			(unlocked yes)
			(layer "F.Fab")
			(hide yes)
			(effects
				(font
					(size 1.016 1.016)
					(thickness 0.1524)
				)
			)
		)
		(property "Device Type" "R402H14"
			(at 0.064008 -5.517896 180)
			(unlocked yes)
			(layer "F.Fab")
			(hide yes)
			(effects
				(font
					(size 1.016 1.016)
					(thickness 0.1524)
				)
			)
		)
		(duplicate_pad_numbers_are_jumpers no)
		(fp_rect
			(start -0.381 0.8382)
			(end 0.381 -0.8382)
			(stroke
				(width 0)
				(type default)
			)
			(fill no)
			(layer "F.CrtYd")
		)
		(fp_rect
			(start -0.381 0.8382)
			(end 0.381 -0.8382)
			(stroke
				(width 0)
				(type default)
			)
			(fill no)
			(layer "F.Fab")
		)
		(pad "1" smd custom
			(at 0 -0.4318 180)
			(size 0.127 0.127)
			(layers "F.Cu" "F.Mask" "F.Paste")
			(net "PV_VDDR")
			(options
				(clearance outline)
				(anchor circle)
			)
			(primitives
				(gr_poly
					(pts
						(arc
							(start -0.2032 -0.2794)
							(mid -0.239121 -0.264521)
							(end -0.254 -0.2286)
						)
						(arc
							(start -0.254 0.2286)
							(mid -0.239121 0.264521)
							(end -0.2032 0.2794)
						)
						(arc
							(start 0.2032 0.2794)
							(mid 0.239121 0.264521)
							(end 0.254 0.2286)
						)
						(arc
							(start 0.254 -0.2286)
							(mid 0.239121 -0.264521)
							(end 0.2032 -0.2794)
						)
					)
					(width 0)
					(fill yes)
				)
			)
		)
		(pad "2" smd custom
			(at 0 0.4318 180)
			(size 0.127 0.127)
			(layers "F.Cu" "F.Mask" "F.Paste")
			(net "PV_VDDR_VREF_B_FB")
			(options
				(clearance outline)
				(anchor circle)
			)
			(primitives
				(gr_poly
					(pts
						(arc
							(start -0.2032 -0.2794)
							(mid -0.239121 -0.264521)
							(end -0.254 -0.2286)
						)
						(arc
							(start -0.254 0.2286)
							(mid -0.239121 0.264521)
							(end -0.2032 0.2794)
						)
						(arc
							(start 0.2032 0.2794)
							(mid 0.239121 0.264521)
							(end 0.254 0.2286)
						)
						(arc
							(start 0.254 -0.2286)
							(mid 0.239121 -0.264521)
							(end 0.2032 -0.2794)
						)
					)
					(width 0)
					(fill yes)
				)
			)
		)
	)
)
